# T6G (Grand Teton) — schematic netlist excerpt (pin names and nets, part order shuffled) for the footprints in the layout excerpt that follows; sources: Cadence DE-HDL packaged netlist, KiCad conversion of 04192023_DAF0TMB3IC0_F0TG_MB_C_brd_V02_OCP.brd

PR2518  Q_RES  10 1% CHIP  pkg 0402LF  page 266 : A = P12V_HSC_ADC_N ; B = P12V_HSC_SENSE2_R4_N
PR532  Q_RES  0 5% CHIP  pkg 0402LF  page 200 : A = NC_PVDDCR_CPU1_P0_IMON7 ; B = GND
C6615  Q_CAP_DIFFBUS  DIFF BUS_0.22UF 6.3V 20% X6S  pkg C0201  page 308 : \1\ = P5E_CPU0_P3_TX_BUF_C_DP<9> ; \2\ = P5E_CPU0_P3_TX_BUF_DP<9>

(kicad_pcb
	(version 20260206)
	(generator "pcbnew")
	(generator_version "10.0")
	(general
		(thickness 1.6)
		(legacy_teardrops no)
	)
	(paper "A4")
	(title_block
		(title "04192023_DAF0TMB3IC0_F0TG_MB_C_brd_V02_OCP.brd")
		(comment 1 "Grand Teton / footprints 6844-6846 of 8354")
	)
	(layers
		(0 "F.Cu" signal "TOP")
		(4 "In1.Cu" signal "GND")
		(6 "In2.Cu" signal "IN1")
		(8 "In3.Cu" signal "GND1")
		(10 "In4.Cu" signal "IN2")
		(12 "In5.Cu" signal "GND2")
		(14 "In6.Cu" signal "IN3")
		(16 "In7.Cu" signal "GND3")
		(18 "In8.Cu" signal "VCC")
		(20 "In9.Cu" signal "VCC1")
		(22 "In10.Cu" signal "GND4")
		(24 "In11.Cu" signal "IN4")
		(26 "In12.Cu" signal "GND5")
		(28 "In13.Cu" signal "IN5")
		(30 "In14.Cu" signal "GND6")
		(32 "In15.Cu" signal "IN6")
		(34 "In16.Cu" signal "GND7")
		(2 "B.Cu" signal "BOTTOM")
		(9 "F.Adhes" user "F.Adhesive")
		(11 "B.Adhes" user "B.Adhesive")
		(13 "F.Paste" user "Package Geometry/Pastemask Top")
		(15 "B.Paste" user "Package Geometry/Pastemask Bottom")
		(5 "F.SilkS" user "Ref Des/Silkscreen Top")
		(7 "B.SilkS" user "Ref Des/Silkscreen Bottom")
		(1 "F.Mask" user "Board Geometry/Soldermask Top")
		(3 "B.Mask" user "Board Geometry/Soldermask Bottom")
		(17 "Dwgs.User" user "User.Drawings")
		(19 "Cmts.User" user "User.Comments")
		(21 "Eco1.User" user "User.Eco1")
		(23 "Eco2.User" user "User.Eco2")
		(25 "Edge.Cuts" user "Board Geometry/Outline")
		(27 "Margin" user)
		(31 "F.CrtYd" user "Package Geometry/Place Bound Top")
		(29 "B.CrtYd" user "Package Geometry/Place Bound Bottom")
		(35 "F.Fab" user "Ref Des/Assembly Top")
		(33 "B.Fab" user "Ref Des/Assembly Bottom")
	)
	(footprint ""
		(layer "B.Cu")
		(at 208.461356 -383.612136)
		(property "Reference" "PR2518"
			(at 0 0 0)
			(layer "B.SilkS")
			(hide yes)
			(effects
				(font
					(size 1.27 1.27)
				)
				(justify mirror)
			)
		)
		(property "Value" ""
			(at 0 0 0)
			(layer "B.Fab")
			(effects
				(font
					(size 1.27 1.27)
				)
				(justify mirror)
			)
		)
		(duplicate_pad_numbers_are_jumpers no)
		(fp_line
			(start -0.7874 -0.4064)
			(end -0.7874 0.4064)
			(stroke
				(width 0.1524)
				(type default)
			)
			(layer "B.SilkS")
		)
		(fp_line
			(start -0.7874 0.4064)
			(end 0.7874 0.4064)
			(stroke
				(width 0.1524)
				(type default)
			)
			(layer "B.SilkS")
		)
		(fp_line
			(start 0.7874 -0.4064)
			(end -0.7874 -0.4064)
			(stroke
				(width 0.1524)
				(type default)
			)
			(layer "B.SilkS")
		)
		(fp_line
			(start 0.7874 0.4064)
			(end 0.7874 -0.4064)
			(stroke
				(width 0.1524)
				(type default)
			)
			(layer "B.SilkS")
		)
		(fp_line
			(start -0.67945 -0.3048)
			(end -0.67945 0.3048)
			(stroke
				(width 0.1)
				(type default)
			)
			(layer "B.Fab")
		)
		(fp_line
			(start -0.67945 0.3048)
			(end -0.120396 0.3048)
			(stroke
				(width 0.1)
				(type default)
			)
			(layer "B.Fab")
		)
		(fp_line
			(start -0.12065 -0.3048)
			(end -0.67945 -0.3048)
			(stroke
				(width 0.1)
				(type default)
			)
			(layer "B.Fab")
		)
		(fp_line
			(start -0.12065 -0.2794)
			(end -0.12065 -0.3048)
			(stroke
				(width 0.1)
				(type default)
			)
			(layer "B.Fab")
		)
		(fp_line
			(start -0.120396 0.2794)
			(end 0.12065 0.2794)
			(stroke
				(width 0.1)
				(type default)
			)
			(layer "B.Fab")
		)
		(fp_line
			(start -0.120396 0.3048)
			(end -0.120396 0.2794)
			(stroke
				(width 0.1)
				(type default)
			)
			(layer "B.Fab")
		)
		(fp_line
			(start 0.12065 -0.305054)
			(end 0.12065 -0.2794)
			(stroke
				(width 0.1)
				(type default)
			)
			(layer "B.Fab")
		)
		(fp_line
			(start 0.12065 -0.2794)
			(end -0.12065 -0.2794)
			(stroke
				(width 0.1)
				(type default)
			)
			(layer "B.Fab")
		)
		(fp_line
			(start 0.12065 0.2794)
			(end 0.12065 0.3048)
			(stroke
				(width 0.1)
				(type default)
			)
			(layer "B.Fab")
		)
		(fp_line
			(start 0.12065 0.3048)
			(end 0.67945 0.3048)
			(stroke
				(width 0.1)
				(type default)
			)
			(layer "B.Fab")
		)
		(fp_line
			(start 0.67945 -0.305054)
			(end 0.12065 -0.305054)
			(stroke
				(width 0.1)
				(type default)
			)
			(layer "B.Fab")
		)
		(fp_line
			(start 0.67945 0.3048)
			(end 0.67945 -0.305054)
			(stroke
				(width 0.1)
				(type default)
			)
			(layer "B.Fab")
		)
		(pad "1" smd circle
			(at 0.40005 0 180)
			(size 0 0)
			(layers "B.Cu" "B.Mask" "B.Paste")
			(net "P12V_HSC_ADC_N")
		)
		(pad "2" smd circle
			(at -0.40005 0 180)
			(size 0 0)
			(layers "B.Cu" "B.Mask" "B.Paste")
			(net "P12V_HSC_SENSE2_R4_N")
		)
	)
	(footprint ""
		(layer "B.Cu")
		(at 400.883882 -416.899344 90)
		(property "Reference" "C6615"
			(at 0 0 90)
			(layer "B.SilkS")
			(hide yes)
			(effects
				(font
					(size 1.27 1.27)
				)
				(justify mirror)
			)
		)
		(property "Value" ""
			(at 0 0 90)
			(layer "B.Fab")
			(effects
				(font
					(size 1.27 1.27)
				)
				(justify mirror)
			)
		)
		(duplicate_pad_numbers_are_jumpers no)
		(fp_line
			(start 0.299974 -0.150114)
			(end -0.299974 -0.150114)
			(stroke
				(width 0.1)
				(type default)
			)
			(layer "B.Fab")
		)
		(fp_line
			(start -0.299974 -0.150114)
			(end -0.299974 0.150114)
			(stroke
				(width 0.1)
				(type default)
			)
			(layer "B.Fab")
		)
		(fp_line
			(start 0.299974 0.150114)
			(end 0.299974 -0.150114)
			(stroke
				(width 0.1)
				(type default)
			)
			(layer "B.Fab")
		)
		(fp_line
			(start -0.299974 0.150114)
			(end 0.299974 0.150114)
			(stroke
				(width 0.1)
				(type default)
			)
			(layer "B.Fab")
		)
		(pad "1" smd rect
			(at 0.2667 0 270)
			(size 0.3048 0.381)
			(layers "B.Cu" "B.Mask" "B.Paste")
			(net "P5E_CPU0_P3_TX_BUF_C_DP<9>")
		)
		(pad "2" smd rect
			(at -0.2667 0 270)
			(size 0.3048 0.381)
			(layers "B.Cu" "B.Mask" "B.Paste")
			(net "P5E_CPU0_P3_TX_BUF_DP<9>")
		)
	)
	(footprint ""
		(layer "B.Cu")
		(at 312.674 -358.14 -90)
		(property "Reference" "PR532"
			(at 0 0 90)
			(layer "B.SilkS")
			(hide yes)
			(effects
				(font
					(size 1.27 1.27)
				)
				(justify mirror)
			)
		)
		(property "Value" ""
			(at 0 0 90)
			(layer "B.Fab")
			(effects
				(font
					(size 1.27 1.27)
				)
				(justify mirror)
			)
		)
		(duplicate_pad_numbers_are_jumpers no)
		(fp_line
			(start -0.7874 0.4064)
			(end 0.7874 0.4064)
			(stroke
				(width 0.1524)
				(type default)
			)
			(layer "B.SilkS")
		)
		(fp_line
			(start 0.7874 0.4064)
			(end 0.7874 -0.4064)
			(stroke
				(width 0.1524)
				(type default)
			)
			(layer "B.SilkS")
		)
		(fp_line
			(start -0.7874 -0.4064)
			(end -0.7874 0.4064)
			(stroke
				(width 0.1524)
				(type default)
			)
			(layer "B.SilkS")
		)
		(fp_line
			(start 0.7874 -0.4064)
			(end -0.7874 -0.4064)
			(stroke
				(width 0.1524)
				(type default)
			)
			(layer "B.SilkS")
		)
		(fp_line
			(start -0.67945 0.3048)
			(end -0.120396 0.3048)
			(stroke
				(width 0.1)
				(type default)
			)
			(layer "B.Fab")
		)
		(fp_line
			(start -0.120396 0.3048)
			(end -0.120396 0.2794)
			(stroke
				(width 0.1)
				(type default)
			)
			(layer "B.Fab")
		)
		(fp_line
			(start 0.12065 0.3048)
			(end 0.67945 0.3048)
			(stroke
				(width 0.1)
				(type default)
			)
			(layer "B.Fab")
		)
		(fp_line
			(start 0.67945 0.3048)
			(end 0.67945 -0.305054)
			(stroke
				(width 0.1)
				(type default)
			)
			(layer "B.Fab")
		)
		(fp_line
			(start -0.120396 0.2794)
			(end 0.12065 0.2794)
			(stroke
				(width 0.1)
				(type default)
			)
			(layer "B.Fab")
		)
		(fp_line
			(start 0.12065 0.2794)
			(end 0.12065 0.3048)
			(stroke
				(width 0.1)
				(type default)
			)
			(layer "B.Fab")
		)
		(fp_line
			(start -0.12065 -0.2794)
			(end -0.12065 -0.3048)
			(stroke
				(width 0.1)
				(type default)
			)
			(layer "B.Fab")
		)
		(fp_line
			(start 0.12065 -0.2794)
			(end -0.12065 -0.2794)
			(stroke
				(width 0.1)
				(type default)
			)
			(layer "B.Fab")
		)
		(fp_line
			(start -0.67945 -0.3048)
			(end -0.67945 0.3048)
			(stroke
				(width 0.1)
				(type default)
			)
			(layer "B.Fab")
		)
		(fp_line
			(start -0.12065 -0.3048)
			(end -0.67945 -0.3048)
			(stroke
				(width 0.1)
				(type default)
			)
			(layer "B.Fab")
		)
		(fp_line
			(start 0.12065 -0.305054)
			(end 0.12065 -0.2794)
			(stroke
				(width 0.1)
				(type default)
			)
			(layer "B.Fab")
		)
		(fp_line
			(start 0.67945 -0.305054)
			(end 0.12065 -0.305054)
			(stroke
				(width 0.1)
				(type default)
			)
			(layer "B.Fab")
		)
		(pad "1" smd circle
			(at 0.40005 0 90)
			(size 0 0)
			(layers "B.Cu" "B.Mask" "B.Paste")
			(net "NC_PVDDCR_CPU1_P0_IMON7")
		)
		(pad "2" smd circle
			(at -0.40005 0 90)
			(size 0 0)
			(layers "B.Cu" "B.Mask" "B.Paste")
			(net "GND")
		)
	)
)
